# S9S_MB_2U (Grand Teton) — schematic netlist excerpt (pin names and nets, part order shuffled) for the footprints in the layout excerpt that follows; sources: Cadence DE-HDL packaged netlist, KiCad conversion of 03242023_DA0F0TMBIJ0_F0T_Motherboard_J_brd_V01_OCP.brd

R4136  Q_RES  100K 1% EMPTY  pkg 0402LF  page 146 : A = PRSNT_CABLE_GPU_A2_N ; B = GND

(kicad_pcb
	(version 20260206)
	(generator "pcbnew")
	(generator_version "10.0")
	(general
		(thickness 1.6)
		(legacy_teardrops no)
	)
	(paper "A4")
	(title_block
		(title "03242023_DA0F0TMBIJ0_F0T_Motherboard_J_brd_V01_OCP.brd")
		(comment 1 "Grand Teton / footprints 1235-1235 of 6105")
	)
	(layers
		(0 "F.Cu" signal "TOP")
		(4 "In1.Cu" signal "GND")
		(6 "In2.Cu" signal "IN1")
		(8 "In3.Cu" signal "GND1")
		(10 "In4.Cu" signal "IN2")
		(12 "In5.Cu" signal "GND2")
		(14 "In6.Cu" signal "IN3")
		(16 "In7.Cu" signal "GND3")
		(18 "In8.Cu" signal "VCC")
		(20 "In9.Cu" signal "VCC1")
		(22 "In10.Cu" signal "GND4")
		(24 "In11.Cu" signal "IN4")
		(26 "In12.Cu" signal "GND5")
		(28 "In13.Cu" signal "IN5")
		(30 "In14.Cu" signal "GND6")
		(32 "In15.Cu" signal "IN6")
		(34 "In16.Cu" signal "GND7")
		(2 "B.Cu" signal "BOTTOM")
		(9 "F.Adhes" user "F.Adhesive")
		(11 "B.Adhes" user "B.Adhesive")
		(13 "F.Paste" user "Package Geometry/Pastemask Top")
		(15 "B.Paste" user "Package Geometry/Pastemask Bottom")
		(5 "F.SilkS" user "Ref Des/Silkscreen Top")
		(7 "B.SilkS" user "Ref Des/Silkscreen Bottom")
		(1 "F.Mask" user "Board Geometry/Soldermask Top")
		(3 "B.Mask" user "Board Geometry/Soldermask Bottom")
		(17 "Dwgs.User" user "User.Drawings")
		(19 "Cmts.User" user "User.Comments")
		(21 "Eco1.User" user "User.Eco1")
		(23 "Eco2.User" user "User.Eco2")
		(25 "Edge.Cuts" user "Board Geometry/Outline")
		(27 "Margin" user)
		(31 "F.CrtYd" user "Package Geometry/Place Bound Top")
		(29 "B.CrtYd" user "Package Geometry/Place Bound Bottom")
		(35 "F.Fab" user "Ref Des/Assembly Top")
		(33 "B.Fab" user "Ref Des/Assembly Bottom")
	)
	(footprint ""
		(layer "F.Cu")
		(at 305.58994 -430.6697 -90)
		(property "Reference" "R4136"
			(at 0 0 270)
			(layer "F.SilkS")
			(hide yes)
			(effects
				(font
					(size 1.27 1.27)
				)
			)
		)
		(property "Value" ""
			(at 0 0 270)
			(layer "F.Fab")
			(effects
				(font
					(size 1.27 1.27)
				)
			)
		)
		(duplicate_pad_numbers_are_jumpers no)
		(fp_line
			(start -0.7874 0.4064)
			(end -0.7874 -0.4064)
			(stroke
				(width 0.1524)
				(type default)
			)
			(layer "F.SilkS")
		)
		(fp_line
			(start 0.7874 0.4064)
			(end -0.7874 0.4064)
			(stroke
				(width 0.1524)
				(type default)
			)
			(layer "F.SilkS")
		)
		(fp_line
			(start -0.7874 -0.4064)
			(end 0.7874 -0.4064)
			(stroke
				(width 0.1524)
				(type default)
			)
			(layer "F.SilkS")
		)
		(fp_line
			(start 0.7874 -0.4064)
			(end 0.7874 0.4064)
			(stroke
				(width 0.1524)
				(type default)
			)
			(layer "F.SilkS")
		)
		(fp_line
			(start -0.67945 0.3048)
			(end -0.67945 -0.305054)
			(stroke
				(width 0.1)
				(type default)
			)
			(layer "F.Fab")
		)
		(fp_line
			(start -0.12065 0.3048)
			(end -0.67945 0.3048)
			(stroke
				(width 0.1)
				(type default)
			)
			(layer "F.Fab")
		)
		(fp_line
			(start 0.120396 0.3048)
			(end 0.120396 0.2794)
			(stroke
				(width 0.1)
				(type default)
			)
			(layer "F.Fab")
		)
		(fp_line
			(start 0.67945 0.3048)
			(end 0.120396 0.3048)
			(stroke
				(width 0.1)
				(type default)
			)
			(layer "F.Fab")
		)
		(fp_line
			(start -0.12065 0.2794)
			(end -0.12065 0.3048)
			(stroke
				(width 0.1)
				(type default)
			)
			(layer "F.Fab")
		)
		(fp_line
			(start 0.120396 0.2794)
			(end -0.12065 0.2794)
			(stroke
				(width 0.1)
				(type default)
			)
			(layer "F.Fab")
		)
		(fp_line
			(start -0.12065 -0.2794)
			(end 0.12065 -0.2794)
			(stroke
				(width 0.1)
				(type default)
			)
			(layer "F.Fab")
		)
		(fp_line
			(start 0.12065 -0.2794)
			(end 0.12065 -0.3048)
			(stroke
				(width 0.1)
				(type default)
			)
			(layer "F.Fab")
		)
		(fp_line
			(start 0.12065 -0.3048)
			(end 0.67945 -0.3048)
			(stroke
				(width 0.1)
				(type default)
			)
			(layer "F.Fab")
		)
		(fp_line
			(start 0.67945 -0.3048)
			(end 0.67945 0.3048)
			(stroke
				(width 0.1)
				(type default)
			)
			(layer "F.Fab")
		)
		(fp_line
			(start -0.67945 -0.305054)
			(end -0.12065 -0.305054)
			(stroke
				(width 0.1)
				(type default)
			)
			(layer "F.Fab")
		)
		(fp_line
			(start -0.12065 -0.305054)
			(end -0.12065 -0.2794)
			(stroke
				(width 0.1)
				(type default)
			)
			(layer "F.Fab")
		)
		(pad "1" smd circle
			(at -0.40005 0 270)
			(size 0 0)
			(layers "F.Cu" "F.Mask" "F.Paste")
			(net "PRSNT_CABLE_GPU_A2_N")
		)
		(pad "2" smd circle
			(at 0.40005 0 270)
			(size 0 0)
			(layers "F.Cu" "F.Mask" "F.Paste")
			(net "GND")
		)
	)
)
